# T6G (Grand Teton) — schematic netlist excerpt (pin names and nets, part order shuffled) for the footprints in the layout excerpt that follows; sources: Cadence DE-HDL packaged netlist, KiCad conversion of 04192023_DAF0TMB3IC0_F0TG_MB_C_brd_V02_OCP.brd

R696  Q_RES  49.9 1% CHIP  pkg 0201LF  page 353 : A = SMB_RT_CPU1_P3_ROM_MUX_1D_SDA ; B = SMB_RT_CPU1_P3_ROM_MUX_1D_R_SDA
C155  Q_CAP  10UF 25V 10% X6S  pkg C0805  page 91 : A = P12V_MEM_CPU0 ; B = GND
C417  Q_CAP  22UF 4V 20% X6S  pkg C0402  page 345 : A = P0V9_CPU1_RT2_2A ; B = GND

(kicad_pcb
	(version 20260206)
	(generator "pcbnew")
	(generator_version "10.0")
	(general
		(thickness 1.6)
		(legacy_teardrops no)
	)
	(paper "A4")
	(title_block
		(title "04192023_DAF0TMB3IC0_F0TG_MB_C_brd_V02_OCP.brd")
		(comment 1 "Grand Teton / footprints 6344-6346 of 8354")
	)
	(layers
		(0 "F.Cu" signal "TOP")
		(4 "In1.Cu" signal "GND")
		(6 "In2.Cu" signal "IN1")
		(8 "In3.Cu" signal "GND1")
		(10 "In4.Cu" signal "IN2")
		(12 "In5.Cu" signal "GND2")
		(14 "In6.Cu" signal "IN3")
		(16 "In7.Cu" signal "GND3")
		(18 "In8.Cu" signal "VCC")
		(20 "In9.Cu" signal "VCC1")
		(22 "In10.Cu" signal "GND4")
		(24 "In11.Cu" signal "IN4")
		(26 "In12.Cu" signal "GND5")
		(28 "In13.Cu" signal "IN5")
		(30 "In14.Cu" signal "GND6")
		(32 "In15.Cu" signal "IN6")
		(34 "In16.Cu" signal "GND7")
		(2 "B.Cu" signal "BOTTOM")
		(9 "F.Adhes" user "F.Adhesive")
		(11 "B.Adhes" user "B.Adhesive")
		(13 "F.Paste" user "Package Geometry/Pastemask Top")
		(15 "B.Paste" user "Package Geometry/Pastemask Bottom")
		(5 "F.SilkS" user "Ref Des/Silkscreen Top")
		(7 "B.SilkS" user "Ref Des/Silkscreen Bottom")
		(1 "F.Mask" user "Board Geometry/Soldermask Top")
		(3 "B.Mask" user "Board Geometry/Soldermask Bottom")
		(17 "Dwgs.User" user "User.Drawings")
		(19 "Cmts.User" user "User.Comments")
		(21 "Eco1.User" user "User.Eco1")
		(23 "Eco2.User" user "User.Eco2")
		(25 "Edge.Cuts" user "Board Geometry/Outline")
		(27 "Margin" user)
		(31 "F.CrtYd" user "Package Geometry/Place Bound Top")
		(29 "B.CrtYd" user "Package Geometry/Place Bound Bottom")
		(35 "F.Fab" user "Ref Des/Assembly Top")
		(33 "B.Fab" user "Ref Des/Assembly Bottom")
	)
	(footprint ""
		(layer "B.Cu")
		(at 265.54811 -192.660016 180)
		(property "Reference" "C155"
			(at 0 0 0)
			(layer "B.SilkS")
			(hide yes)
			(effects
				(font
					(size 1.27 1.27)
				)
				(justify mirror)
			)
		)
		(property "Value" ""
			(at 0 0 0)
			(layer "B.Fab")
			(effects
				(font
					(size 1.27 1.27)
				)
				(justify mirror)
			)
		)
		(duplicate_pad_numbers_are_jumpers no)
		(fp_line
			(start 1.524 0.762)
			(end 1.524 -0.762)
			(stroke
				(width 0.1524)
				(type default)
			)
			(layer "B.SilkS")
		)
		(fp_line
			(start 1.524 -0.762)
			(end -1.524 -0.762)
			(stroke
				(width 0.1524)
				(type default)
			)
			(layer "B.SilkS")
		)
		(fp_line
			(start -1.524 0.762)
			(end 1.524 0.762)
			(stroke
				(width 0.1524)
				(type default)
			)
			(layer "B.SilkS")
		)
		(fp_line
			(start -1.524 -0.762)
			(end -1.524 0.762)
			(stroke
				(width 0.1524)
				(type default)
			)
			(layer "B.SilkS")
		)
		(fp_line
			(start 1.1049 0.724916)
			(end -1.1049 0.724916)
			(stroke
				(width 0.1)
				(type default)
			)
			(layer "B.Fab")
		)
		(fp_line
			(start 1.1049 -0.724916)
			(end 1.1049 0.724916)
			(stroke
				(width 0.1)
				(type default)
			)
			(layer "B.Fab")
		)
		(fp_line
			(start -1.1049 0.724916)
			(end -1.1049 -0.724916)
			(stroke
				(width 0.1)
				(type default)
			)
			(layer "B.Fab")
		)
		(fp_line
			(start -1.1049 -0.724916)
			(end 1.1049 -0.724916)
			(stroke
				(width 0.1)
				(type default)
			)
			(layer "B.Fab")
		)
		(pad "1" smd rect
			(at 0.889 0 180)
			(size 1.016 1.27)
			(layers "B.Cu" "B.Mask" "B.Paste")
			(net "P12V_MEM_CPU0")
		)
		(pad "2" smd rect
			(at -0.889 0 180)
			(size 1.016 1.27)
			(layers "B.Cu" "B.Mask" "B.Paste")
			(net "GND")
		)
	)
	(footprint ""
		(layer "B.Cu")
		(at 148.218906 -390.560052 90)
		(property "Reference" "C417"
			(at 0 0 90)
			(layer "B.SilkS")
			(hide yes)
			(effects
				(font
					(size 1.27 1.27)
				)
				(justify mirror)
			)
		)
		(property "Value" ""
			(at 0 0 90)
			(layer "B.Fab")
			(effects
				(font
					(size 1.27 1.27)
				)
				(justify mirror)
			)
		)
		(duplicate_pad_numbers_are_jumpers no)
		(fp_line
			(start 0.7874 -0.4064)
			(end -0.7874 -0.4064)
			(stroke
				(width 0.1524)
				(type default)
			)
			(layer "B.SilkS")
		)
		(fp_line
			(start -0.7874 -0.4064)
			(end -0.7874 0.4064)
			(stroke
				(width 0.1524)
				(type default)
			)
			(layer "B.SilkS")
		)
		(fp_line
			(start 0.7874 0.4064)
			(end 0.7874 -0.4064)
			(stroke
				(width 0.1524)
				(type default)
			)
			(layer "B.SilkS")
		)
		(fp_line
			(start -0.7874 0.4064)
			(end 0.7874 0.4064)
			(stroke
				(width 0.1524)
				(type default)
			)
			(layer "B.SilkS")
		)
		(fp_line
			(start 0.67945 -0.305054)
			(end 0.12065 -0.305054)
			(stroke
				(width 0.1)
				(type default)
			)
			(layer "B.Fab")
		)
		(fp_line
			(start 0.12065 -0.305054)
			(end 0.12065 -0.2794)
			(stroke
				(width 0.1)
				(type default)
			)
			(layer "B.Fab")
		)
		(fp_line
			(start -0.12065 -0.3048)
			(end -0.67945 -0.3048)
			(stroke
				(width 0.1)
				(type default)
			)
			(layer "B.Fab")
		)
		(fp_line
			(start -0.67945 -0.3048)
			(end -0.67945 0.3048)
			(stroke
				(width 0.1)
				(type default)
			)
			(layer "B.Fab")
		)
		(fp_line
			(start 0.12065 -0.2794)
			(end -0.12065 -0.2794)
			(stroke
				(width 0.1)
				(type default)
			)
			(layer "B.Fab")
		)
		(fp_line
			(start -0.12065 -0.2794)
			(end -0.12065 -0.3048)
			(stroke
				(width 0.1)
				(type default)
			)
			(layer "B.Fab")
		)
		(fp_line
			(start 0.12065 0.2794)
			(end 0.12065 0.3048)
			(stroke
				(width 0.1)
				(type default)
			)
			(layer "B.Fab")
		)
		(fp_line
			(start -0.120396 0.2794)
			(end 0.12065 0.2794)
			(stroke
				(width 0.1)
				(type default)
			)
			(layer "B.Fab")
		)
		(fp_line
			(start 0.67945 0.3048)
			(end 0.67945 -0.305054)
			(stroke
				(width 0.1)
				(type default)
			)
			(layer "B.Fab")
		)
		(fp_line
			(start 0.12065 0.3048)
			(end 0.67945 0.3048)
			(stroke
				(width 0.1)
				(type default)
			)
			(layer "B.Fab")
		)
		(fp_line
			(start -0.120396 0.3048)
			(end -0.120396 0.2794)
			(stroke
				(width 0.1)
				(type default)
			)
			(layer "B.Fab")
		)
		(fp_line
			(start -0.67945 0.3048)
			(end -0.120396 0.3048)
			(stroke
				(width 0.1)
				(type default)
			)
			(layer "B.Fab")
		)
		(pad "1" smd circle
			(at 0.40005 0 270)
			(size 0 0)
			(layers "B.Cu" "B.Mask" "B.Paste")
			(net "P0V9_CPU1_RT2_2A")
		)
		(pad "2" smd circle
			(at -0.40005 0 270)
			(size 0 0)
			(layers "B.Cu" "B.Mask" "B.Paste")
			(net "GND")
		)
	)
	(footprint ""
		(layer "B.Cu")
		(at 112.35436 -408.651456 90)
		(property "Reference" "R696"
			(at 0 0 90)
			(layer "B.SilkS")
			(hide yes)
			(effects
				(font
					(size 1.27 1.27)
				)
				(justify mirror)
			)
		)
		(property "Value" ""
			(at 0 0 90)
			(layer "B.Fab")
			(effects
				(font
					(size 1.27 1.27)
				)
				(justify mirror)
			)
		)
		(duplicate_pad_numbers_are_jumpers no)
		(fp_line
			(start 0.32512 -0.175006)
			(end -0.32512 -0.175006)
			(stroke
				(width 0.1)
				(type default)
			)
			(layer "B.Fab")
		)
		(fp_line
			(start -0.32512 -0.175006)
			(end -0.32512 0.175006)
			(stroke
				(width 0.1)
				(type default)
			)
			(layer "B.Fab")
		)
		(fp_line
			(start 0.32512 0.175006)
			(end 0.32512 -0.175006)
			(stroke
				(width 0.1)
				(type default)
			)
			(layer "B.Fab")
		)
		(fp_line
			(start -0.32512 0.175006)
			(end 0.32512 0.175006)
			(stroke
				(width 0.1)
				(type default)
			)
			(layer "B.Fab")
		)
		(pad "1" smd rect
			(at 0.2667 0 270)
			(size 0.3048 0.381)
			(layers "B.Cu" "B.Mask" "B.Paste")
			(net "SMB_RT_CPU1_P3_ROM_MUX_1D_SDA")
		)
		(pad "2" smd rect
			(at -0.2667 0 90)
			(size 0.3048 0.381)
			(layers "B.Cu" "B.Mask" "B.Paste")
			(net "SMB_RT_CPU1_P3_ROM_MUX_1D_R_SDA")
		)
	)
)
